# SCM (Grand Teton) — schematic netlist excerpt (pin names and nets, part order shuffled) for the footprints in the layout excerpt that follows; sources: Cadence DE-HDL packaged netlist, KiCad conversion of 12092022_DA0F0TMDCD0_F0T_Management_Board_D_brd_V3_OCP.brd

C32  Q_CAP  1UF 25V 10% X6S  pkg C0402  page 13 : A = P3V3_P2V5_P1V8_RVDD ; B = GND

U26  74HC1G126GW  IC  pkg TSSOP5_0-65_2-05X1-25  page 23
  \1\  = BMC_DDC_BUF_EN
  \2\  = V_VGAVS
  GND  = GND
  \4\  = V_VGAVS_BUF_R
  \5\  = BMC_DDC_BUF_PWR

(kicad_pcb
	(version 20260206)
	(generator "pcbnew")
	(generator_version "10.0")
	(general
		(thickness 1.6)
		(legacy_teardrops no)
	)
	(paper "A4")
	(title_block
		(title "12092022_DA0F0TMDCD0_F0T_Management_Board_D_brd_V3_OCP.brd")
		(comment 1 "Grand Teton / footprints 949-950 of 1440")
	)
	(layers
		(0 "F.Cu" signal "TOP")
		(4 "In1.Cu" signal "GND")
		(6 "In2.Cu" signal "IN1")
		(8 "In3.Cu" signal "GND1")
		(10 "In4.Cu" signal "IN2")
		(12 "In5.Cu" signal "VCC")
		(14 "In6.Cu" signal "VCC1")
		(16 "In7.Cu" signal "IN3")
		(18 "In8.Cu" signal "GND2")
		(20 "In9.Cu" signal "IN4")
		(22 "In10.Cu" signal "GND3")
		(2 "B.Cu" signal "BOTTOM")
		(9 "F.Adhes" user "F.Adhesive")
		(11 "B.Adhes" user "B.Adhesive")
		(13 "F.Paste" user "Package Geometry/Pastemask Top")
		(15 "B.Paste" user "Package Geometry/Pastemask Bottom")
		(5 "F.SilkS" user "Ref Des/Silkscreen Top")
		(7 "B.SilkS" user "Ref Des/Silkscreen Bottom")
		(1 "F.Mask" user "Board Geometry/Soldermask Top")
		(3 "B.Mask" user "Board Geometry/Soldermask Bottom")
		(17 "Dwgs.User" user "User.Drawings")
		(19 "Cmts.User" user "User.Comments")
		(21 "Eco1.User" user "User.Eco1")
		(23 "Eco2.User" user "User.Eco2")
		(25 "Edge.Cuts" user "Board Geometry/Outline")
		(27 "Margin" user)
		(31 "F.CrtYd" user "Package Geometry/Place Bound Top")
		(29 "B.CrtYd" user "Package Geometry/Place Bound Bottom")
		(35 "F.Fab" user "Ref Des/Assembly Top")
		(33 "B.Fab" user "Ref Des/Assembly Bottom")
	)
	(footprint ""
		(layer "B.Cu")
		(at 43.5356 -4.1148 -90)
		(property "Reference" "U26"
			(at -2.047748 -2.3876 0)
			(unlocked yes)
			(layer "B.SilkS")
			(effects
				(font
					(size 0.7874 0.5842)
					(thickness 0.1524)
				)
				(justify left mirror)
			)
		)
		(property "Value" ""
			(at 0 0 90)
			(layer "B.Fab")
			(effects
				(font
					(size 1.27 1.27)
				)
				(justify mirror)
			)
		)
		(duplicate_pad_numbers_are_jumpers no)
		(fp_line
			(start -1.3462 1.1938)
			(end -1.3462 -1.1938)
			(stroke
				(width 0.1524)
				(type default)
			)
			(layer "B.SilkS")
		)
		(fp_line
			(start 1.3462 1.1938)
			(end -1.3462 1.1938)
			(stroke
				(width 0.1524)
				(type default)
			)
			(layer "B.SilkS")
		)
		(fp_line
			(start -1.3462 -1.1938)
			(end 1.3462 -1.1938)
			(stroke
				(width 0.1524)
				(type default)
			)
			(layer "B.SilkS")
		)
		(fp_line
			(start 1.3462 -1.1938)
			(end 1.3462 1.1684)
			(stroke
				(width 0.1524)
				(type default)
			)
			(layer "B.SilkS")
		)
		(fp_poly
			(pts
				(xy 1.447038 -0.760476) (xy 2.052066 -0.457962) (xy 2.052066 -1.06299)
			)
			(stroke
				(width 0)
				(type default)
			)
			(fill yes)
			(layer "B.SilkS")
		)
		(fp_line
			(start -0.674878 1.124966)
			(end -0.674878 -1.124966)
			(stroke
				(width 0.1)
				(type default)
			)
			(layer "B.Fab")
		)
		(fp_line
			(start 0.674878 1.124966)
			(end -0.674878 1.124966)
			(stroke
				(width 0.1)
				(type default)
			)
			(layer "B.Fab")
		)
		(fp_line
			(start -0.674878 -1.124966)
			(end 0.674878 -1.124966)
			(stroke
				(width 0.1)
				(type default)
			)
			(layer "B.Fab")
		)
		(fp_line
			(start 0.674878 -1.124966)
			(end 0.674878 1.124966)
			(stroke
				(width 0.1)
				(type default)
			)
			(layer "B.Fab")
		)
		(fp_poly
			(pts
				(xy 1.447038 -0.760476) (xy 2.052066 -0.457962) (xy 2.052066 -1.06299)
			)
			(stroke
				(width 0)
				(type default)
			)
			(fill yes)
			(layer "B.Fab")
		)
		(pad "1" smd rect
			(at 0.899922 -0.750062 90)
			(size 0.6096 0.6096)
			(layers "B.Cu" "B.Mask" "B.Paste")
			(net "BMC_DDC_BUF_EN")
		)
		(pad "2" smd rect
			(at 0.899922 0)
			(size 0.4064 0.6096)
			(layers "B.Cu" "B.Mask" "B.Paste")
			(net "V_VGAVS")
		)
		(pad "3" smd rect
			(at 0.899922 0.750062 90)
			(size 0.6096 0.6096)
			(layers "B.Cu" "B.Mask" "B.Paste")
			(net "GND")
		)
		(pad "4" smd rect
			(at -0.899922 0.750062 90)
			(size 0.6096 0.6096)
			(layers "B.Cu" "B.Mask" "B.Paste")
			(net "V_VGAVS_BUF_R")
		)
		(pad "5" smd rect
			(at -0.899922 -0.750062 90)
			(size 0.6096 0.6096)
			(layers "B.Cu" "B.Mask" "B.Paste")
			(net "BMC_DDC_BUF_PWR")
		)
	)
	(footprint ""
		(layer "B.Cu")
		(at 50.508662 -46.220126 180)
		(property "Reference" "C32"
			(at 0 0 0)
			(layer "B.SilkS")
			(hide yes)
			(effects
				(font
					(size 1.27 1.27)
				)
				(justify mirror)
			)
		)
		(property "Value" ""
			(at 0 0 0)
			(layer "B.Fab")
			(effects
				(font
					(size 1.27 1.27)
				)
				(justify mirror)
			)
		)
		(duplicate_pad_numbers_are_jumpers no)
		(fp_line
			(start 0.7874 0.4064)
			(end 0.7874 -0.4064)
			(stroke
				(width 0.1524)
				(type default)
			)
			(layer "B.SilkS")
		)
		(fp_line
			(start 0.7874 -0.4064)
			(end -0.7874 -0.4064)
			(stroke
				(width 0.1524)
				(type default)
			)
			(layer "B.SilkS")
		)
		(fp_line
			(start -0.7874 0.4064)
			(end 0.7874 0.4064)
			(stroke
				(width 0.1524)
				(type default)
			)
			(layer "B.SilkS")
		)
		(fp_line
			(start -0.7874 -0.4064)
			(end -0.7874 0.4064)
			(stroke
				(width 0.1524)
				(type default)
			)
			(layer "B.SilkS")
		)
		(fp_line
			(start 0.67945 0.3048)
			(end 0.67945 -0.305054)
			(stroke
				(width 0.1)
				(type default)
			)
			(layer "B.Fab")
		)
		(fp_line
			(start 0.67945 -0.305054)
			(end 0.12065 -0.305054)
			(stroke
				(width 0.1)
				(type default)
			)
			(layer "B.Fab")
		)
		(fp_line
			(start 0.12065 0.3048)
			(end 0.67945 0.3048)
			(stroke
				(width 0.1)
				(type default)
			)
			(layer "B.Fab")
		)
		(fp_line
			(start 0.12065 0.2794)
			(end 0.12065 0.3048)
			(stroke
				(width 0.1)
				(type default)
			)
			(layer "B.Fab")
		)
		(fp_line
			(start 0.12065 -0.2794)
			(end -0.12065 -0.2794)
			(stroke
				(width 0.1)
				(type default)
			)
			(layer "B.Fab")
		)
		(fp_line
			(start 0.12065 -0.305054)
			(end 0.12065 -0.2794)
			(stroke
				(width 0.1)
				(type default)
			)
			(layer "B.Fab")
		)
		(fp_line
			(start -0.120396 0.3048)
			(end -0.120396 0.2794)
			(stroke
				(width 0.1)
				(type default)
			)
			(layer "B.Fab")
		)
		(fp_line
			(start -0.120396 0.2794)
			(end 0.12065 0.2794)
			(stroke
				(width 0.1)
				(type default)
			)
			(layer "B.Fab")
		)
		(fp_line
			(start -0.12065 -0.2794)
			(end -0.12065 -0.3048)
			(stroke
				(width 0.1)
				(type default)
			)
			(layer "B.Fab")
		)
		(fp_line
			(start -0.12065 -0.3048)
			(end -0.67945 -0.3048)
			(stroke
				(width 0.1)
				(type default)
			)
			(layer "B.Fab")
		)
		(fp_line
			(start -0.67945 0.3048)
			(end -0.120396 0.3048)
			(stroke
				(width 0.1)
				(type default)
			)
			(layer "B.Fab")
		)
		(fp_line
			(start -0.67945 -0.3048)
			(end -0.67945 0.3048)
			(stroke
				(width 0.1)
				(type default)
			)
			(layer "B.Fab")
		)
		(pad "1" smd circle
			(at 0.40005 0)
			(size 0 0)
			(layers "B.Cu" "B.Mask" "B.Paste")
			(net "P3V3_P2V5_P1V8_RVDD")
		)
		(pad "2" smd circle
			(at -0.40005 0)
			(size 0 0)
			(layers "B.Cu" "B.Mask" "B.Paste")
			(net "GND")
		)
	)
)
